# T6G (Grand Teton) — schematic netlist excerpt (pin names and nets, part order shuffled) for the footprints in the layout excerpt that follows; sources: Cadence DE-HDL packaged netlist, KiCad conversion of 04192023_DAF0TMB3IC0_F0TG_MB_C_brd_V02_OCP.brd

C217  Q_CAP  0.1UF 10V 10% X7S  pkg C0201  page 334 : A = P1V8_CPU1_RT1_1A ; B = GND
C6052  Q_CAP  0.1UF 25V 10% X7R  pkg 0402  page 177 : A = P3V3_AUX ; B = GND
PR533  Q_RES  0 5% CHIP  pkg 0402LF  page 217 : A = NC_PVDDCR_CPU1_P1_IMON7 ; B = GND

(kicad_pcb
	(version 20260206)
	(generator "pcbnew")
	(generator_version "10.0")
	(general
		(thickness 1.6)
		(legacy_teardrops no)
	)
	(paper "A4")
	(title_block
		(title "04192023_DAF0TMB3IC0_F0TG_MB_C_brd_V02_OCP.brd")
		(comment 1 "Grand Teton / footprints 6069-6071 of 8354")
	)
	(layers
		(0 "F.Cu" signal "TOP")
		(4 "In1.Cu" signal "GND")
		(6 "In2.Cu" signal "IN1")
		(8 "In3.Cu" signal "GND1")
		(10 "In4.Cu" signal "IN2")
		(12 "In5.Cu" signal "GND2")
		(14 "In6.Cu" signal "IN3")
		(16 "In7.Cu" signal "GND3")
		(18 "In8.Cu" signal "VCC")
		(20 "In9.Cu" signal "VCC1")
		(22 "In10.Cu" signal "GND4")
		(24 "In11.Cu" signal "IN4")
		(26 "In12.Cu" signal "GND5")
		(28 "In13.Cu" signal "IN5")
		(30 "In14.Cu" signal "GND6")
		(32 "In15.Cu" signal "IN6")
		(34 "In16.Cu" signal "GND7")
		(2 "B.Cu" signal "BOTTOM")
		(9 "F.Adhes" user "F.Adhesive")
		(11 "B.Adhes" user "B.Adhesive")
		(13 "F.Paste" user "Package Geometry/Pastemask Top")
		(15 "B.Paste" user "Package Geometry/Pastemask Bottom")
		(5 "F.SilkS" user "Ref Des/Silkscreen Top")
		(7 "B.SilkS" user "Ref Des/Silkscreen Bottom")
		(1 "F.Mask" user "Board Geometry/Soldermask Top")
		(3 "B.Mask" user "Board Geometry/Soldermask Bottom")
		(17 "Dwgs.User" user "User.Drawings")
		(19 "Cmts.User" user "User.Comments")
		(21 "Eco1.User" user "User.Eco1")
		(23 "Eco2.User" user "User.Eco2")
		(25 "Edge.Cuts" user "Board Geometry/Outline")
		(27 "Margin" user)
		(31 "F.CrtYd" user "Package Geometry/Place Bound Top")
		(29 "B.CrtYd" user "Package Geometry/Place Bound Bottom")
		(35 "F.Fab" user "Ref Des/Assembly Top")
		(33 "B.Fab" user "Ref Des/Assembly Bottom")
	)
	(footprint ""
		(layer "B.Cu")
		(at 33.02 -361.569 -90)
		(property "Reference" "PR533"
			(at 0 0 90)
			(layer "B.SilkS")
			(hide yes)
			(effects
				(font
					(size 1.27 1.27)
				)
				(justify mirror)
			)
		)
		(property "Value" ""
			(at 0 0 90)
			(layer "B.Fab")
			(effects
				(font
					(size 1.27 1.27)
				)
				(justify mirror)
			)
		)
		(duplicate_pad_numbers_are_jumpers no)
		(fp_line
			(start -0.7874 0.4064)
			(end 0.7874 0.4064)
			(stroke
				(width 0.1524)
				(type default)
			)
			(layer "B.SilkS")
		)
		(fp_line
			(start 0.7874 0.4064)
			(end 0.7874 -0.4064)
			(stroke
				(width 0.1524)
				(type default)
			)
			(layer "B.SilkS")
		)
		(fp_line
			(start -0.7874 -0.4064)
			(end -0.7874 0.4064)
			(stroke
				(width 0.1524)
				(type default)
			)
			(layer "B.SilkS")
		)
		(fp_line
			(start 0.7874 -0.4064)
			(end -0.7874 -0.4064)
			(stroke
				(width 0.1524)
				(type default)
			)
			(layer "B.SilkS")
		)
		(fp_line
			(start -0.67945 0.3048)
			(end -0.120396 0.3048)
			(stroke
				(width 0.1)
				(type default)
			)
			(layer "B.Fab")
		)
		(fp_line
			(start -0.120396 0.3048)
			(end -0.120396 0.2794)
			(stroke
				(width 0.1)
				(type default)
			)
			(layer "B.Fab")
		)
		(fp_line
			(start 0.12065 0.3048)
			(end 0.67945 0.3048)
			(stroke
				(width 0.1)
				(type default)
			)
			(layer "B.Fab")
		)
		(fp_line
			(start 0.67945 0.3048)
			(end 0.67945 -0.305054)
			(stroke
				(width 0.1)
				(type default)
			)
			(layer "B.Fab")
		)
		(fp_line
			(start -0.120396 0.2794)
			(end 0.12065 0.2794)
			(stroke
				(width 0.1)
				(type default)
			)
			(layer "B.Fab")
		)
		(fp_line
			(start 0.12065 0.2794)
			(end 0.12065 0.3048)
			(stroke
				(width 0.1)
				(type default)
			)
			(layer "B.Fab")
		)
		(fp_line
			(start -0.12065 -0.2794)
			(end -0.12065 -0.3048)
			(stroke
				(width 0.1)
				(type default)
			)
			(layer "B.Fab")
		)
		(fp_line
			(start 0.12065 -0.2794)
			(end -0.12065 -0.2794)
			(stroke
				(width 0.1)
				(type default)
			)
			(layer "B.Fab")
		)
		(fp_line
			(start -0.67945 -0.3048)
			(end -0.67945 0.3048)
			(stroke
				(width 0.1)
				(type default)
			)
			(layer "B.Fab")
		)
		(fp_line
			(start -0.12065 -0.3048)
			(end -0.67945 -0.3048)
			(stroke
				(width 0.1)
				(type default)
			)
			(layer "B.Fab")
		)
		(fp_line
			(start 0.12065 -0.305054)
			(end 0.12065 -0.2794)
			(stroke
				(width 0.1)
				(type default)
			)
			(layer "B.Fab")
		)
		(fp_line
			(start 0.67945 -0.305054)
			(end 0.12065 -0.305054)
			(stroke
				(width 0.1)
				(type default)
			)
			(layer "B.Fab")
		)
		(pad "1" smd circle
			(at 0.40005 0 90)
			(size 0 0)
			(layers "B.Cu" "B.Mask" "B.Paste")
			(net "NC_PVDDCR_CPU1_P1_IMON7")
		)
		(pad "2" smd circle
			(at -0.40005 0 90)
			(size 0 0)
			(layers "B.Cu" "B.Mask" "B.Paste")
			(net "GND")
		)
	)
	(footprint ""
		(layer "B.Cu")
		(at 135.858504 -31.874206 -90)
		(property "Reference" "C6052"
			(at 0 0 90)
			(layer "B.SilkS")
			(hide yes)
			(effects
				(font
					(size 1.27 1.27)
				)
				(justify mirror)
			)
		)
		(property "Value" ""
			(at 0 0 90)
			(layer "B.Fab")
			(effects
				(font
					(size 1.27 1.27)
				)
				(justify mirror)
			)
		)
		(duplicate_pad_numbers_are_jumpers no)
		(fp_line
			(start -0.7874 0.4064)
			(end 0.7874 0.4064)
			(stroke
				(width 0.1524)
				(type default)
			)
			(layer "B.SilkS")
		)
		(fp_line
			(start 0.7874 0.4064)
			(end 0.7874 -0.4064)
			(stroke
				(width 0.1524)
				(type default)
			)
			(layer "B.SilkS")
		)
		(fp_line
			(start -0.7874 -0.4064)
			(end -0.7874 0.4064)
			(stroke
				(width 0.1524)
				(type default)
			)
			(layer "B.SilkS")
		)
		(fp_line
			(start 0.7874 -0.4064)
			(end -0.7874 -0.4064)
			(stroke
				(width 0.1524)
				(type default)
			)
			(layer "B.SilkS")
		)
		(fp_line
			(start -0.67945 0.3048)
			(end -0.120396 0.3048)
			(stroke
				(width 0.1)
				(type default)
			)
			(layer "B.Fab")
		)
		(fp_line
			(start -0.120396 0.3048)
			(end -0.120396 0.2794)
			(stroke
				(width 0.1)
				(type default)
			)
			(layer "B.Fab")
		)
		(fp_line
			(start 0.12065 0.3048)
			(end 0.67945 0.3048)
			(stroke
				(width 0.1)
				(type default)
			)
			(layer "B.Fab")
		)
		(fp_line
			(start 0.67945 0.3048)
			(end 0.67945 -0.305054)
			(stroke
				(width 0.1)
				(type default)
			)
			(layer "B.Fab")
		)
		(fp_line
			(start -0.120396 0.2794)
			(end 0.12065 0.2794)
			(stroke
				(width 0.1)
				(type default)
			)
			(layer "B.Fab")
		)
		(fp_line
			(start 0.12065 0.2794)
			(end 0.12065 0.3048)
			(stroke
				(width 0.1)
				(type default)
			)
			(layer "B.Fab")
		)
		(fp_line
			(start -0.12065 -0.2794)
			(end -0.12065 -0.3048)
			(stroke
				(width 0.1)
				(type default)
			)
			(layer "B.Fab")
		)
		(fp_line
			(start 0.12065 -0.2794)
			(end -0.12065 -0.2794)
			(stroke
				(width 0.1)
				(type default)
			)
			(layer "B.Fab")
		)
		(fp_line
			(start -0.67945 -0.3048)
			(end -0.67945 0.3048)
			(stroke
				(width 0.1)
				(type default)
			)
			(layer "B.Fab")
		)
		(fp_line
			(start -0.12065 -0.3048)
			(end -0.67945 -0.3048)
			(stroke
				(width 0.1)
				(type default)
			)
			(layer "B.Fab")
		)
		(fp_line
			(start 0.12065 -0.305054)
			(end 0.12065 -0.2794)
			(stroke
				(width 0.1)
				(type default)
			)
			(layer "B.Fab")
		)
		(fp_line
			(start 0.67945 -0.305054)
			(end 0.12065 -0.305054)
			(stroke
				(width 0.1)
				(type default)
			)
			(layer "B.Fab")
		)
		(pad "1" smd circle
			(at 0.40005 0 90)
			(size 0 0)
			(layers "B.Cu" "B.Mask" "B.Paste")
			(net "P3V3_AUX")
		)
		(pad "2" smd circle
			(at -0.40005 0 90)
			(size 0 0)
			(layers "B.Cu" "B.Mask" "B.Paste")
			(net "GND")
		)
	)
	(footprint ""
		(layer "B.Cu")
		(at 89.506298 -386.766562 90)
		(property "Reference" "C217"
			(at 0 0 90)
			(layer "B.SilkS")
			(hide yes)
			(effects
				(font
					(size 1.27 1.27)
				)
				(justify mirror)
			)
		)
		(property "Value" ""
			(at 0 0 90)
			(layer "B.Fab")
			(effects
				(font
					(size 1.27 1.27)
				)
				(justify mirror)
			)
		)
		(duplicate_pad_numbers_are_jumpers no)
		(fp_line
			(start 0.299974 -0.150114)
			(end -0.299974 -0.150114)
			(stroke
				(width 0.1)
				(type default)
			)
			(layer "B.Fab")
		)
		(fp_line
			(start -0.299974 -0.150114)
			(end -0.299974 0.150114)
			(stroke
				(width 0.1)
				(type default)
			)
			(layer "B.Fab")
		)
		(fp_line
			(start 0.299974 0.150114)
			(end 0.299974 -0.150114)
			(stroke
				(width 0.1)
				(type default)
			)
			(layer "B.Fab")
		)
		(fp_line
			(start -0.299974 0.150114)
			(end 0.299974 0.150114)
			(stroke
				(width 0.1)
				(type default)
			)
			(layer "B.Fab")
		)
		(pad "1" smd rect
			(at 0.2667 0 270)
			(size 0.3048 0.381)
			(layers "B.Cu" "B.Mask" "B.Paste")
			(net "P1V8_CPU1_RT1_1A")
		)
		(pad "2" smd rect
			(at -0.2667 0 270)
			(size 0.3048 0.381)
			(layers "B.Cu" "B.Mask" "B.Paste")
			(net "GND")
		)
	)
)
